# BASEBOARD_FAB2 (Tioga Pass) — schematic netlist excerpt (pin names and nets, part order shuffled) for the footprints in the layout excerpt that follows; sources: Cadence DE-HDL packaged netlist, KiCad conversion of Wiwynn_Tioga_Pass_MB.brd

RT27  1R3F-GP  1%  pkg RCL_GP  page 203 : \1\ = VR_PVCCIN_CPU0_PHASE4_RC ; \2\ = GND
R4C8  RES  1.00K 1% CHIP  pkg 0402  page 96 : A = P3V3_STBY ; B = PU_GTL2014_2_DIR
L7A4  IND-300NH-20-GP  pkg DISCRET-GB1  page 236 : S = VR_P1V05_PCH_STBY_PH1_PHASE_SW ; F = P1V05_PCH_STBY

(kicad_pcb
	(version 20260206)
	(generator "pcbnew")
	(generator_version "10.0")
	(general
		(thickness 1.6)
		(legacy_teardrops no)
	)
	(paper "A4")
	(title_block
		(title "Wiwynn_Tioga_Pass_MB.brd")
		(comment 1 "Tioga Pass / footprints 138-140 of 4770")
	)
	(layers
		(0 "F.Cu" signal "TOP")
		(4 "In1.Cu" signal "L2GND")
		(6 "In2.Cu" signal "L3")
		(8 "In3.Cu" signal "L4GND")
		(10 "In4.Cu" signal "L5")
		(12 "In5.Cu" signal "L6GND")
		(14 "In6.Cu" signal "L7VCC")
		(16 "In7.Cu" signal "L8VCC")
		(18 "In8.Cu" signal "L9GND")
		(20 "In9.Cu" signal "L10")
		(22 "In10.Cu" signal "L11GND")
		(24 "In11.Cu" signal "L12")
		(26 "In12.Cu" signal "L13GND")
		(2 "B.Cu" signal "BOTTOM")
		(9 "F.Adhes" user "F.Adhesive")
		(11 "B.Adhes" user "B.Adhesive")
		(13 "F.Paste" user "Package Geometry/Pastemask Top")
		(15 "B.Paste" user "Package Geometry/Pastemask Bottom")
		(5 "F.SilkS" user "Ref Des/Silkscreen Top")
		(7 "B.SilkS" user "Ref Des/Silkscreen Bottom")
		(1 "F.Mask" user "Board Geometry/Soldermask Top")
		(3 "B.Mask" user "Board Geometry/Soldermask Bottom")
		(17 "Dwgs.User" user "User.Drawings")
		(19 "Cmts.User" user "User.Comments")
		(21 "Eco1.User" user "User.Eco1")
		(23 "Eco2.User" user "User.Eco2")
		(25 "Edge.Cuts" user "Board Geometry/Outline")
		(27 "Margin" user)
		(31 "F.CrtYd" user "Package Geometry/Place Bound Top")
		(29 "B.CrtYd" user "Package Geometry/Place Bound Bottom")
		(35 "F.Fab" user "Ref Des/Assembly Top")
		(33 "B.Fab" user "Ref Des/Assembly Bottom")
	)
	(footprint ""
		(layer "F.Cu")
		(at 172.5676 -93.3958 180)
		(property "Reference" "R4C8"
			(at 0 0 180)
			(layer "F.SilkS")
			(hide yes)
			(effects
				(font
					(size 1.27 1.27)
				)
			)
		)
		(property "Value" ""
			(at 0 0 180)
			(layer "F.Fab")
			(effects
				(font
					(size 1.27 1.27)
				)
			)
		)
		(duplicate_pad_numbers_are_jumpers no)
		(fp_poly
			(pts
				(xy -0.2794 -0.1016) (xy 0.2794 -0.1016) (xy 0.2794 0.9906) (xy -0.2794 0.9906)
			)
			(stroke
				(width 0)
				(type default)
			)
			(fill no)
			(layer "F.CrtYd")
		)
		(fp_line
			(start 0.2794 0.9906)
			(end 0.2794 -0.1016)
			(stroke
				(width 0.1)
				(type default)
			)
			(layer "F.Fab")
		)
		(fp_line
			(start 0.2794 -0.1016)
			(end -0.2794 -0.1016)
			(stroke
				(width 0.1)
				(type default)
			)
			(layer "F.Fab")
		)
		(fp_line
			(start -0.2794 0.9906)
			(end 0.2794 0.9906)
			(stroke
				(width 0.1)
				(type default)
			)
			(layer "F.Fab")
		)
		(fp_line
			(start -0.2794 -0.1016)
			(end -0.2794 0.9906)
			(stroke
				(width 0.1)
				(type default)
			)
			(layer "F.Fab")
		)
		(pad "1" smd rect
			(at 0 0 180)
			(size 0.508 0.508)
			(layers "F.Cu" "F.Mask" "F.Paste")
			(net "P3V3_STBY")
		)
		(pad "2" smd rect
			(at 0 0.889 180)
			(size 0.508 0.508)
			(layers "F.Cu" "F.Mask" "F.Paste")
			(net "PU_GTL2014_2_DIR")
		)
		(zone
			(layer "F.Cu")
			(hatch none 0.5)
			(connect_pads
				(clearance 0)
			)
			(min_thickness 0.25)
			(keepout
				(tracks not_allowed)
				(vias allowed)
				(pads allowed)
				(copperpour not_allowed)
				(footprints allowed)
			)
			(placement
				(enabled no)
				(sheetname "")
			)
			(fill
				(thermal_gap 0.5)
				(thermal_bridge_width 0.5)
				(island_removal_mode 0)
			)
			(polygon
				(pts
					(xy 172.8216 -94.0308) (xy 172.3136 -94.0308) (xy 172.3136 -93.6498) (xy 172.8216 -93.6498)
				)
			)
		)
		(zone
			(layer "F.Cu")
			(hatch none 0.5)
			(connect_pads
				(clearance 0)
			)
			(min_thickness 0.25)
			(keepout
				(tracks allowed)
				(vias not_allowed)
				(pads allowed)
				(copperpour not_allowed)
				(footprints allowed)
			)
			(placement
				(enabled no)
				(sheetname "")
			)
			(fill
				(thermal_gap 0.5)
				(thermal_bridge_width 0.5)
				(island_removal_mode 0)
			)
			(polygon
				(pts
					(xy 172.8216 -93.6498) (xy 172.3136 -93.6498) (xy 172.3136 -94.0308) (xy 172.8216 -94.0308)
				)
			)
		)
	)
	(footprint ""
		(layer "F.Cu")
		(at 384.4798 -146.574764)
		(property "Reference" "L7A4"
			(at 3.378708 -4.251706 0)
			(unlocked yes)
			(layer "F.SilkS")
			(effects
				(font
					(size 0.4064 0.254)
					(thickness 0.1524)
				)
			)
		)
		(property "Value" ""
			(at 0 0 0)
			(layer "F.Fab")
			(effects
				(font
					(size 1.27 1.27)
				)
			)
		)
		(duplicate_pad_numbers_are_jumpers no)
		(fp_line
			(start -1.1303 -3.199892)
			(end 8.3693 -3.199892)
			(stroke
				(width 0.1524)
				(type default)
			)
			(layer "F.SilkS")
		)
		(fp_line
			(start -1.1303 -1.6637)
			(end -1.1303 -3.199892)
			(stroke
				(width 0.1524)
				(type default)
			)
			(layer "F.SilkS")
		)
		(fp_line
			(start -1.1303 3.199892)
			(end -1.1303 1.6637)
			(stroke
				(width 0.1524)
				(type default)
			)
			(layer "F.SilkS")
		)
		(fp_line
			(start 8.3693 -3.199892)
			(end 8.3693 -1.6637)
			(stroke
				(width 0.1524)
				(type default)
			)
			(layer "F.SilkS")
		)
		(fp_line
			(start 8.3693 1.6637)
			(end 8.3693 3.199892)
			(stroke
				(width 0.1524)
				(type default)
			)
			(layer "F.SilkS")
		)
		(fp_line
			(start 8.3693 3.199892)
			(end -1.1303 3.199892)
			(stroke
				(width 0.1524)
				(type default)
			)
			(layer "F.SilkS")
		)
		(fp_rect
			(start -1.1303 3.199892)
			(end 8.3693 -3.199892)
			(stroke
				(width 0)
				(type default)
			)
			(fill no)
			(layer "F.CrtYd")
		)
		(fp_line
			(start -1.1303 -3.199892)
			(end 8.3693 -3.199892)
			(stroke
				(width 0.1)
				(type default)
			)
			(layer "F.Fab")
		)
		(fp_line
			(start -1.1303 3.199892)
			(end -1.1303 -3.199892)
			(stroke
				(width 0.1)
				(type default)
			)
			(layer "F.Fab")
		)
		(fp_line
			(start 8.3693 -3.199892)
			(end 8.3693 3.199892)
			(stroke
				(width 0.1)
				(type default)
			)
			(layer "F.Fab")
		)
		(fp_line
			(start 8.3693 3.199892)
			(end -1.1303 3.199892)
			(stroke
				(width 0.1)
				(type default)
			)
			(layer "F.Fab")
		)
		(pad "1" smd rect
			(at 0 0)
			(size 3.683 2.667)
			(layers "F.Cu" "F.Mask" "F.Paste")
			(net "VR_P1V05_PCH_STBY_PH1_PHASE_SW")
		)
		(pad "2" smd rect
			(at 7.239 0)
			(size 3.683 2.667)
			(layers "F.Cu" "F.Mask" "F.Paste")
			(net "P1V05_PCH_STBY")
		)
	)
	(footprint ""
		(layer "F.Cu")
		(at 201.87158 -77.47 -90)
		(property "Reference" "RT27"
			(at 0 0 270)
			(layer "F.SilkS")
			(hide yes)
			(effects
				(font
					(size 1.27 1.27)
				)
			)
		)
		(property "Value" "*"
			(at -0.0254 -2.6289 270)
			(unlocked yes)
			(layer "F.Fab")
			(hide yes)
			(effects
				(font
					(size 1.27 1.016)
					(thickness 0.1524)
				)
			)
		)
		(property "Device Type" "1R3F-GP_RCL_GP-1R3F-GP,64.1R00A"
			(at -0.0254 -4.1529 270)
			(unlocked yes)
			(layer "F.Fab")
			(hide yes)
			(effects
				(font
					(size 1.27 1.016)
					(thickness 0.1524)
				)
			)
		)
		(duplicate_pad_numbers_are_jumpers no)
		(fp_line
			(start -0.4826 0)
			(end -0.2032 0)
			(stroke
				(width 0.2032)
				(type default)
			)
			(layer "F.SilkS")
		)
		(fp_line
			(start 0.2032 0)
			(end 0.4826 0)
			(stroke
				(width 0.2032)
				(type default)
			)
			(layer "F.SilkS")
		)
		(fp_rect
			(start -0.5842 1.3335)
			(end 0.5842 -1.3335)
			(stroke
				(width 0)
				(type default)
			)
			(fill no)
			(layer "F.CrtYd")
		)
		(fp_rect
			(start -0.5842 1.3335)
			(end 0.5842 -1.3335)
			(stroke
				(width 0)
				(type default)
			)
			(fill no)
			(layer "F.Fab")
		)
		(pad "1" smd custom
			(at 0 -0.762 270)
			(size 0.2159 0.2159)
			(layers "F.Cu" "F.Mask" "F.Paste")
			(net "VR_PVCCIN_CPU0_PHASE4_RC")
			(options
				(clearance outline)
				(anchor circle)
			)
			(primitives
				(gr_poly
					(pts
						(arc
							(start -0.3302 -0.4318)
							(mid -0.402042 -0.402042)
							(end -0.4318 -0.3302)
						)
						(arc
							(start -0.4318 0.3302)
							(mid -0.402042 0.402042)
							(end -0.3302 0.4318)
						)
						(arc
							(start 0.3302 0.4318)
							(mid 0.402042 0.402042)
							(end 0.4318 0.3302)
						)
						(arc
							(start 0.4318 -0.3302)
							(mid 0.402042 -0.402042)
							(end 0.3302 -0.4318)
						)
					)
					(width 0)
					(fill yes)
				)
			)
		)
		(pad "2" smd custom
			(at 0 0.762 270)
			(size 0.2159 0.2159)
			(layers "F.Cu" "F.Mask" "F.Paste")
			(net "GND")
			(options
				(clearance outline)
				(anchor circle)
			)
			(primitives
				(gr_poly
					(pts
						(arc
							(start -0.3302 -0.4318)
							(mid -0.402042 -0.402042)
							(end -0.4318 -0.3302)
						)
						(arc
							(start -0.4318 0.3302)
							(mid -0.402042 0.402042)
							(end -0.3302 0.4318)
						)
						(arc
							(start 0.3302 0.4318)
							(mid 0.402042 0.402042)
							(end 0.4318 0.3302)
						)
						(arc
							(start 0.4318 -0.3302)
							(mid 0.402042 -0.402042)
							(end 0.3302 -0.4318)
						)
					)
					(width 0)
					(fill yes)
				)
			)
		)
	)
)
